(kicad_pcb
	(version 20241229)
	(generator "pcbnew")
	(generator_version "9.0")
	(general
		(thickness 1.294)
		(legacy_teardrops no)
	)
	(paper "A3")
	(title_block
		(title "Kintex 410T devboard")
		(date "2024-04-03")
		(rev "1.1.2")
		(comment 9 "footprints 338-342 of 975")
	)
	(layers
		(0 "F.Cu" mixed)
		(4 "In1.Cu" power)
		(6 "In2.Cu" power)
		(8 "In3.Cu" mixed)
		(10 "In4.Cu" power)
		(12 "In5.Cu" mixed)
		(14 "In6.Cu" power)
		(16 "In7.Cu" mixed)
		(18 "In8.Cu" power)
		(2 "B.Cu" mixed)
		(9 "F.Adhes" user "F.Adhesive")
		(11 "B.Adhes" user "B.Adhesive")
		(13 "F.Paste" user)
		(15 "B.Paste" user)
		(5 "F.SilkS" user "F.Silkscreen")
		(7 "B.SilkS" user "B.Silkscreen")
		(1 "F.Mask" user)
		(3 "B.Mask" user)
		(17 "Dwgs.User" user "User.Drawings")
		(19 "Cmts.User" user "User.Comments")
		(21 "Eco1.User" user "User.Eco1")
		(23 "Eco2.User" user "User.Eco2")
		(25 "Edge.Cuts" user)
		(27 "Margin" user)
		(31 "F.CrtYd" user "F.Courtyard")
		(29 "B.CrtYd" user "B.Courtyard")
		(35 "F.Fab" user)
		(33 "B.Fab" user)
	)
	(footprint "antmicro-footprints:R_0402_1005Metric"
		(layer "F.Cu")
		(at 254.445 136.835 180)
		(descr "Resistor SMD 0402")
		(tags "resistor SMD 0402")
		(property "Reference" "R160"
			(at 1.395 4.835 180)
			(layer "F.SilkS")
			(effects
				(font
					(size 0.7 0.7)
					(thickness 0.15)
				)
				(justify left bottom)
			)
		)
		(property "Value" "R_12k_0402"
			(at 0 1.4 180)
			(layer "F.Fab")
			(effects
				(font
					(size 0.7 0.7)
					(thickness 0.15)
				)
				(justify left bottom)
			)
		)
		(property "Description" "SMD Chip Resistor, 12 kohm, ± 1%, 62.5 mW, 0402 [1005 Metric], Thick Film, General Purpose"
			(at 0 0 180)
			(layer "F.Fab")
			(hide yes)
			(effects
				(font
					(size 1.27 1.27)
					(thickness 0.15)
				)
			)
		)
		(property "Author" "Antmicro"
			(at 508.89 273.67 0)
			(layer "F.Fab")
			(hide yes)
			(effects
				(font
					(size 1 1)
					(thickness 0.15)
				)
			)
		)
		(property "License" "Apache-2.0"
			(at 508.89 273.67 0)
			(layer "F.Fab")
			(hide yes)
			(effects
				(font
					(size 1 1)
					(thickness 0.15)
				)
			)
		)
		(property "MPN" "CR0402-FX-1202GLF"
			(at 508.89 273.67 0)
			(layer "F.Fab")
			(hide yes)
			(effects
				(font
					(size 1 1)
					(thickness 0.15)
				)
			)
		)
		(property "Manufacturer" "Bourns"
			(at 508.89 273.67 0)
			(layer "F.Fab")
			(hide yes)
			(effects
				(font
					(size 1 1)
					(thickness 0.15)
				)
			)
		)
		(property "Tolerance" "1%"
			(at 508.89 273.67 0)
			(layer "F.Fab")
			(hide yes)
			(effects
				(font
					(size 1 1)
					(thickness 0.15)
				)
			)
		)
		(property "Val" "12k"
			(at 508.89 273.67 0)
			(layer "F.Fab")
			(hide yes)
			(effects
				(font
					(size 1 1)
					(thickness 0.15)
				)
			)
		)
		(sheetname "USB PHY")
		(sheetfile "usb-phy.kicad_sch")
		(attr smd)
		(fp_rect
			(start -0.925 -0.47)
			(end 0.925 0.47)
			(stroke
				(width 0.05)
				(type default)
			)
			(fill no)
			(layer "F.CrtYd")
		)
		(fp_rect
			(start -0.5 -0.25)
			(end 0.5 0.25)
			(stroke
				(width 0.15)
				(type solid)
			)
			(fill no)
			(layer "F.Fab")
		)
		(pad "1" smd roundrect
			(at -0.48 0 180)
			(size 0.59 0.64)
			(layers "F.Cu" "F.Mask" "F.Paste")
			(roundrect_rratio 0.25)
			(net 1 "GND")
			(pintype "passive")
		)
		(pad "2" smd roundrect
			(at 0.48 0 180)
			(size 0.59 0.64)
			(layers "F.Cu" "F.Mask" "F.Paste")
			(roundrect_rratio 0.25)
			(net 920 "/USB PHY/FTDI_REF")
			(pintype "passive")
		)
	)
	(footprint "antmicro-footprints:R_Array_4x0201_Panasonic_EXB18V"
		(layer "F.Cu")
		(at 245.9 144.302)
		(property "Reference" "R41"
			(at -11.7 -41.852 0)
			(layer "F.SilkS")
			(effects
				(font
					(size 0.7 0.7)
					(thickness 0.15)
				)
				(justify right bottom)
			)
		)
		(property "Value" "R_4x33R_0201_array"
			(at -1.1 1.8 0)
			(layer "F.Fab")
			(effects
				(font
					(size 0.7 0.7)
					(thickness 0.15)
				)
				(justify left bottom)
			)
		)
		(property "Description" "Fixed Network Resistor, 33 ohm, Isolated, 4 Resistors, 0502 [1406 Metric], Flat, ± 5%"
			(at 0 0 0)
			(layer "F.Fab")
			(hide yes)
			(effects
				(font
					(size 1.27 1.27)
					(thickness 0.15)
				)
			)
		)
		(property "Author" "Antmicro"
			(at 0 0 0)
			(layer "F.Fab")
			(hide yes)
			(effects
				(font
					(size 1 1)
					(thickness 0.15)
				)
			)
		)
		(property "License" "Apache-2.0"
			(at 0 0 0)
			(layer "F.Fab")
			(hide yes)
			(effects
				(font
					(size 1 1)
					(thickness 0.15)
				)
			)
		)
		(property "MPN" "EXB-18V330JX"
			(at 0 0 0)
			(layer "F.Fab")
			(hide yes)
			(effects
				(font
					(size 1 1)
					(thickness 0.15)
				)
			)
		)
		(property "Manufacturer" "Panasonic"
			(at 0 0 0)
			(layer "F.Fab")
			(hide yes)
			(effects
				(font
					(size 1 1)
					(thickness 0.15)
				)
			)
		)
		(property "Val" "R_4x33R_0201"
			(at 0 0 0)
			(layer "F.Fab")
			(hide yes)
			(effects
				(font
					(size 1 1)
					(thickness 0.15)
				)
			)
		)
		(sheetname "Supervisior MCU")
		(sheetfile "supervisor-mcu.kicad_sch")
		(attr smd)
		(fp_line
			(start -0.8 -0.45)
			(end -0.8 0.45)
			(stroke
				(width 0.12)
				(type solid)
			)
			(layer "F.SilkS")
		)
		(fp_line
			(start 0.8 -0.45)
			(end 0.8 0.45)
			(stroke
				(width 0.12)
				(type solid)
			)
			(layer "F.SilkS")
		)
		(fp_rect
			(start -0.898 -0.66)
			(end 0.898 0.65)
			(stroke
				(width 0.05)
				(type solid)
			)
			(fill no)
			(layer "F.CrtYd")
		)
		(pad "1" smd roundrect
			(at -0.6 0.298)
			(size 0.2 0.4)
			(layers "F.Cu" "F.Mask" "F.Paste")
			(roundrect_rratio 0.25)
			(net 1098 "/Supervisior MCU/USB_D1")
			(pinfunction "R1.1")
			(pintype "passive")
		)
		(pad "2" smd roundrect
			(at -0.202 0.298)
			(size 0.2 0.4)
			(layers "F.Cu" "F.Mask" "F.Paste")
			(roundrect_rratio 0.25)
			(net 1110 "/Supervisior MCU/USB_D4")
			(pinfunction "R2.1")
			(pintype "passive")
		)
		(pad "3" smd roundrect
			(at 0.2 0.298)
			(size 0.2 0.4)
			(layers "F.Cu" "F.Mask" "F.Paste")
			(roundrect_rratio 0.25)
			(net 1111 "/Supervisior MCU/USB_D5")
			(pinfunction "R3.1")
			(pintype "passive")
		)
		(pad "4" smd roundrect
			(at 0.598 0.298)
			(size 0.2 0.4)
			(layers "F.Cu" "F.Mask" "F.Paste")
			(roundrect_rratio 0.25)
			(net 1102 "/Supervisior MCU/SCL0")
			(pinfunction "R4.1")
			(pintype "passive")
		)
		(pad "5" smd roundrect
			(at 0.598 -0.3)
			(size 0.2 0.4)
			(layers "F.Cu" "F.Mask" "F.Paste")
			(roundrect_rratio 0.25)
			(net 1339 "/SUP_MCU.SCL")
			(pinfunction "R4.2")
			(pintype "passive")
		)
		(pad "6" smd roundrect
			(at 0.2 -0.3)
			(size 0.2 0.4)
			(layers "F.Cu" "F.Mask" "F.Paste")
			(roundrect_rratio 0.25)
			(net 1380 "/SUP_MCU.D5")
			(pinfunction "R3.2")
			(pintype "passive")
		)
		(pad "7" smd roundrect
			(at -0.202 -0.3)
			(size 0.2 0.4)
			(layers "F.Cu" "F.Mask" "F.Paste")
			(roundrect_rratio 0.25)
			(net 1381 "/SUP_MCU.D4")
			(pinfunction "R2.2")
			(pintype "passive")
		)
		(pad "8" smd roundrect
			(at -0.6 -0.3)
			(size 0.2 0.4)
			(layers "F.Cu" "F.Mask" "F.Paste")
			(roundrect_rratio 0.25)
			(net 1382 "/SUP_MCU.D1")
			(pinfunction "R1.2")
			(pintype "passive")
		)
	)
	(footprint "antmicro-footprints:R_0402_1005Metric"
		(layer "F.Cu")
		(at 203.653752 100.5365)
		(descr "Resistor SMD 0402")
		(tags "resistor SMD 0402")
		(property "Reference" "R242"
			(at 5.346248 8.2635 0)
			(layer "F.SilkS")
			(effects
				(font
					(size 0.7 0.7)
					(thickness 0.15)
				)
				(justify left bottom)
			)
		)
		(property "Value" "R_1M_0402"
			(at 0 1.4 0)
			(layer "F.Fab")
			(effects
				(font
					(size 0.7 0.7)
					(thickness 0.15)
				)
				(justify left bottom)
			)
		)
		(property "Description" "SMD Chip Resistor, 1 Mohm, ± 1%, 62.5 mW, 0402 [1005 Metric], Thick Film, General Purpose"
			(at 0 0 0)
			(layer "F.Fab")
			(hide yes)
			(effects
				(font
					(size 1.27 1.27)
					(thickness 0.15)
				)
			)
		)
		(property "Author" "Antmicro"
			(at 0 0 0)
			(layer "F.Fab")
			(hide yes)
			(effects
				(font
					(size 1 1)
					(thickness 0.15)
				)
			)
		)
		(property "License" "Apache-2.0"
			(at 0 0 0)
			(layer "F.Fab")
			(hide yes)
			(effects
				(font
					(size 1 1)
					(thickness 0.15)
				)
			)
		)
		(property "MPN" "CR0402-FX-1004GLF"
			(at 0 0 0)
			(layer "F.Fab")
			(hide yes)
			(effects
				(font
					(size 1 1)
					(thickness 0.15)
				)
			)
		)
		(property "Manufacturer" "Bourns"
			(at 0 0 0)
			(layer "F.Fab")
			(hide yes)
			(effects
				(font
					(size 1 1)
					(thickness 0.15)
				)
			)
		)
		(property "Tolerance" "1%"
			(at 0 0 0)
			(layer "F.Fab")
			(hide yes)
			(effects
				(font
					(size 1 1)
					(thickness 0.15)
				)
			)
		)
		(property "Val" "1M"
			(at 0 0 0)
			(layer "F.Fab")
			(hide yes)
			(effects
				(font
					(size 1 1)
					(thickness 0.15)
				)
			)
		)
		(sheetname "HDMI + Ethernet")
		(sheetfile "hdmi-ethernet.kicad_sch")
		(attr smd)
		(fp_rect
			(start -0.925 -0.47)
			(end 0.925 0.47)
			(stroke
				(width 0.05)
				(type default)
			)
			(fill no)
			(layer "F.CrtYd")
		)
		(fp_rect
			(start -0.5 -0.25)
			(end 0.5 0.25)
			(stroke
				(width 0.15)
				(type solid)
			)
			(fill no)
			(layer "F.Fab")
		)
		(pad "1" smd roundrect
			(at -0.48 0)
			(size 0.59 0.64)
			(layers "F.Cu" "F.Mask" "F.Paste")
			(roundrect_rratio 0.25)
			(net 720 "/HDMI + Ethernet/GBE_XO")
			(pintype "passive")
		)
		(pad "2" smd roundrect
			(at 0.48 0)
			(size 0.59 0.64)
			(layers "F.Cu" "F.Mask" "F.Paste")
			(roundrect_rratio 0.25)
			(net 718 "/HDMI + Ethernet/GBE_XI")
			(pintype "passive")
		)
	)
	(footprint "antmicro-footprints:PinHeader_2x10_P1.27mm_SMD_Shrouded"
		(layer "F.Cu")
		(at 190.000001 82.288501)
		(property "Reference" "J10"
			(at -9.700001 3.711499 0)
			(layer "F.SilkS")
			(effects
				(font
					(size 0.7 0.7)
					(thickness 0.15)
				)
				(justify left bottom)
			)
		)
		(property "Value" "PinHeader_2x10_P1.27mm_SMD_Shrouded"
			(at -3.65 0.37 0)
			(layer "F.Fab")
			(effects
				(font
					(size 0.7 0.7)
					(thickness 0.15)
				)
				(justify left bottom)
			)
		)
		(property "Description" "Pin Header, Wire-to-Board, 1.27 mm, 2 Rows, 20 Contacts, Surface Mount Straight, WR-BHD"
			(at 0 0 0)
			(layer "F.Fab")
			(hide yes)
			(effects
				(font
					(size 1.27 1.27)
					(thickness 0.15)
				)
			)
		)
		(property "Author" "Antmicro"
			(at 0 0 0)
			(layer "F.Fab")
			(hide yes)
			(effects
				(font
					(size 1 1)
					(thickness 0.15)
				)
			)
		)
		(property "License" "Apache-2.0"
			(at 0 0 0)
			(layer "F.Fab")
			(hide yes)
			(effects
				(font
					(size 1 1)
					(thickness 0.15)
				)
			)
		)
		(property "MPN" "62732020621"
			(at 0 0 0)
			(layer "F.Fab")
			(hide yes)
			(effects
				(font
					(size 1 1)
					(thickness 0.15)
				)
			)
		)
		(property "Manufacturer" "Würth Elektronik"
			(at 0 0 0)
			(layer "F.Fab")
			(hide yes)
			(effects
				(font
					(size 1 1)
					(thickness 0.15)
				)
			)
		)
		(sheetname "User GPIO + LED + button + DIP switch")
		(sheetfile "user-gpio.kicad_sch")
		(attr smd)
		(fp_line
			(start -9.6 -2.601)
			(end -9.6 2.6)
			(stroke
				(width 0.15)
				(type solid)
			)
			(layer "F.SilkS")
		)
		(fp_line
			(start -9.6 -2.601)
			(end -6.3 -2.601)
			(stroke
				(width 0.15)
				(type solid)
			)
			(layer "F.SilkS")
		)
		(fp_line
			(start -9.6 2.6)
			(end -6.3 2.6)
			(stroke
				(width 0.15)
				(type solid)
			)
			(layer "F.SilkS")
		)
		(fp_line
			(start 6.299 -2.601)
			(end 9.598 -2.601)
			(stroke
				(width 0.15)
				(type solid)
			)
			(layer "F.SilkS")
		)
		(fp_line
			(start 6.299 2.6)
			(end 9.598 2.6)
			(stroke
				(width 0.15)
				(type solid)
			)
			(layer "F.SilkS")
		)
		(fp_line
			(start 9.598 -2.601)
			(end 9.598 2.6)
			(stroke
				(width 0.15)
				(type solid)
			)
			(layer "F.SilkS")
		)
		(fp_circle
			(center -6.4 3.01)
			(end -6.35 3.01)
			(stroke
				(width 0.15)
				(type solid)
			)
			(fill yes)
			(layer "F.SilkS")
		)
		(fp_rect
			(start -9.9 -3.5)
			(end 9.91 3.5)
			(stroke
				(width 0.05)
				(type solid)
			)
			(fill no)
			(layer "F.CrtYd")
		)
		(fp_line
			(start -9.51 2.59)
			(end -9.31 2.79)
			(stroke
				(width 0.15)
				(type solid)
			)
			(layer "F.Fab")
		)
		(fp_rect
			(start -9.526 -2.806)
			(end 9.525 2.805)
			(stroke
				(width 0.15)
				(type solid)
			)
			(fill no)
			(layer "F.Fab")
		)
		(pad "1" smd rect
			(at -5.715 1.999)
			(size 0.74 2.8)
			(layers "F.Cu" "F.Mask" "F.Paste")
			(net 820 "unconnected-(J10-Pad1)")
			(pintype "passive+no_connect")
		)
		(pad "2" smd rect
			(at -5.715 -2)
			(size 0.74 2.8)
			(layers "F.Cu" "F.Mask" "F.Paste")
			(net 1 "GND")
			(pintype "passive")
		)
		(pad "3" smd rect
			(at -4.446 1.999)
			(size 0.74 2.8)
			(layers "F.Cu" "F.Mask" "F.Paste")
			(net 821 "unconnected-(J10-Pad3)")
			(pintype "passive+no_connect")
		)
		(pad "4" smd rect
			(at -4.446 -2)
			(size 0.74 2.8)
			(layers "F.Cu" "F.Mask" "F.Paste")
			(net 822 "/User GPIO + LED + button + DIP switch/CW_20PIN_HS1")
			(pintype "passive")
		)
		(pad "5" smd rect
			(at -3.177 1.999)
			(size 0.74 2.8)
			(layers "F.Cu" "F.Mask" "F.Paste")
			(net 823 "/User GPIO + LED + button + DIP switch/CW_20PIN_RST")
			(pintype "passive")
		)
		(pad "6" smd rect
			(at -3.177 -2)
			(size 0.74 2.8)
			(layers "F.Cu" "F.Mask" "F.Paste")
			(net 824 "/User GPIO + LED + button + DIP switch/CW_20PIN_HS2")
			(pintype "passive")
		)
		(pad "7" smd rect
			(at -1.905 1.999)
			(size 0.74 2.8)
			(layers "F.Cu" "F.Mask" "F.Paste")
			(net 825 "/User GPIO + LED + button + DIP switch/CW_20PIN_MISO")
			(pintype "passive")
		)
		(pad "8" smd rect
			(at -1.905 -2)
			(size 0.74 2.8)
			(layers "F.Cu" "F.Mask" "F.Paste")
			(net 24 "+3V3")
			(pintype "passive")
		)
		(pad "9" smd rect
			(at -0.635 1.999)
			(size 0.74 2.8)
			(layers "F.Cu" "F.Mask" "F.Paste")
			(net 826 "/User GPIO + LED + button + DIP switch/CW_20PIN_MOSI")
			(pintype "passive")
		)
		(pad "10" smd rect
			(at -0.635 -2)
			(size 0.74 2.8)
			(layers "F.Cu" "F.Mask" "F.Paste")
			(net 827 "/User GPIO + LED + button + DIP switch/CW_20PIN_IO1")
			(pintype "passive")
		)
		(pad "11" smd rect
			(at 0.631 1.999)
			(size 0.74 2.8)
			(layers "F.Cu" "F.Mask" "F.Paste")
			(net 828 "/User GPIO + LED + button + DIP switch/CW_20PIN_TSCK")
			(pintype "passive")
		)
		(pad "12" smd rect
			(at 0.631 -2)
			(size 0.74 2.8)
			(layers "F.Cu" "F.Mask" "F.Paste")
			(net 829 "/User GPIO + LED + button + DIP switch/CW_20PIN_IO2")
			(pintype "passive")
		)
		(pad "13" smd rect
			(at 1.902 1.999)
			(size 0.74 2.8)
			(layers "F.Cu" "F.Mask" "F.Paste")
			(net 830 "/User GPIO + LED + button + DIP switch/CW_20PIN_TPDIC")
			(pintype "passive")
		)
		(pad "14" smd rect
			(at 1.902 -2)
			(size 0.74 2.8)
			(layers "F.Cu" "F.Mask" "F.Paste")
			(net 831 "/User GPIO + LED + button + DIP switch/CW_20PIN_IO3")
			(pintype "passive")
		)
		(pad "15" smd rect
			(at 3.172 1.999)
			(size 0.74 2.8)
			(layers "F.Cu" "F.Mask" "F.Paste")
			(net 832 "/User GPIO + LED + button + DIP switch/CW_20PIN_TPDID")
			(pintype "passive")
		)
		(pad "16" smd rect
			(at 3.172 -2)
			(size 0.74 2.8)
			(layers "F.Cu" "F.Mask" "F.Paste")
			(net 1145 "/User GPIO + LED + button + DIP switch/CW_20PIN_IO4")
			(pintype "passive")
		)
		(pad "17" smd rect
			(at 4.445 1.999)
			(size 0.74 2.8)
			(layers "F.Cu" "F.Mask" "F.Paste")
			(net 1 "GND")
			(pintype "passive")
		)
		(pad "18" smd rect
			(at 4.445 -2)
			(size 0.74 2.8)
			(layers "F.Cu" "F.Mask" "F.Paste")
			(net 833 "unconnected-(J10-Pad18)")
			(pintype "passive+no_connect")
		)
		(pad "19" smd rect
			(at 5.714 1.999)
			(size 0.74 2.8)
			(layers "F.Cu" "F.Mask" "F.Paste")
			(net 1 "GND")
			(pintype "passive")
		)
		(pad "20" smd rect
			(at 5.714 -2)
			(size 0.74 2.8)
			(layers "F.Cu" "F.Mask" "F.Paste")
			(net 834 "unconnected-(J10-Pad20)")
			(pintype "passive+no_connect")
		)
	)
	(footprint "antmicro-footprints:C_0603_1608Metric"
		(layer "F.Cu")
		(at 154.0125 172.7 -90)
		(descr "Capacitor SMD 0603")
		(tags "capacitor 0603")
		(property "Reference" "C329"
			(at -1.025 -0.1125 315)
			(unlocked yes)
			(layer "F.SilkS")
			(effects
				(font
					(size 0.7 0.7)
					(thickness 0.15)
				)
				(justify right bottom)
			)
		)
		(property "Value" "C_22u_0603"
			(at 0 1.6 90)
			(layer "F.Fab")
			(effects
				(font
					(size 0.7 0.7)
					(thickness 0.15)
				)
				(justify right bottom)
			)
		)
		(property "Description" "SMD Multilayer Ceramic Capacitor, 22 µF, 6.3 V, 0603 [1608 Metric], ± 20%, X5R, GRM Series"
			(at 0 0 270)
			(layer "F.Fab")
			(hide yes)
			(effects
				(font
					(size 1.27 1.27)
					(thickness 0.15)
				)
			)
		)
		(property "Author" "Antmicro"
			(at -18.6875 326.7125 0)
			(layer "F.Fab")
			(hide yes)
			(effects
				(font
					(size 1 1)
					(thickness 0.15)
				)
			)
		)
		(property "Dielectric" ""
			(at -18.6875 326.7125 0)
			(layer "F.Fab")
			(hide yes)
			(effects
				(font
					(size 1 1)
					(thickness 0.15)
				)
			)
		)
		(property "License" "Apache-2.0"
			(at -18.6875 326.7125 0)
			(layer "F.Fab")
			(hide yes)
			(effects
				(font
					(size 1 1)
					(thickness 0.15)
				)
			)
		)
		(property "MPN" "GRM188R60J226MEA0D"
			(at -18.6875 326.7125 0)
			(layer "F.Fab")
			(hide yes)
			(effects
				(font
					(size 1 1)
					(thickness 0.15)
				)
			)
		)
		(property "Manufacturer" "Murata"
			(at -18.6875 326.7125 0)
			(layer "F.Fab")
			(hide yes)
			(effects
				(font
					(size 1 1)
					(thickness 0.15)
				)
			)
		)
		(property "Val" "22u"
			(at -18.6875 326.7125 0)
			(layer "F.Fab")
			(hide yes)
			(effects
				(font
					(size 1 1)
					(thickness 0.15)
				)
			)
		)
		(property "Voltage" ""
			(at -18.6875 326.7125 0)
			(layer "F.Fab")
			(hide yes)
			(effects
				(font
					(size 1 1)
					(thickness 0.15)
				)
			)
		)
		(sheetname "DC-DC Converters")
		(sheetfile "dc-dc.kicad_sch")
		(attr smd)
		(fp_line
			(start -0.15 0.4)
			(end 0.15 0.4)
			(stroke
				(width 0.15)
				(type solid)
			)
			(layer "F.SilkS")
		)
		(fp_line
			(start -0.15 -0.4)
			(end 0.15 -0.4)
			(stroke
				(width 0.15)
				(type solid)
			)
			(layer "F.SilkS")
		)
		(fp_rect
			(start -1.25 -0.65)
			(end 1.25 0.65)
			(stroke
				(width 0.05)
				(type solid)
			)
			(fill no)
			(layer "F.CrtYd")
		)
		(fp_rect
			(start -0.8 -0.4)
			(end 0.8 0.4)
			(stroke
				(width 0.15)
				(type solid)
			)
			(fill no)
			(layer "F.Fab")
		)
		(pad "1" smd roundrect
			(at -0.7 0 270)
			(size 0.8 1)
			(layers "F.Cu" "F.Mask" "F.Paste")
			(roundrect_rratio 0.2)
			(net 1 "GND")
			(pintype "passive")
		)
		(pad "2" smd roundrect
			(at 0.7 0 270)
			(size 0.8 1)
			(layers "F.Cu" "F.Mask" "F.Paste")
			(roundrect_rratio 0.2)
			(net 738 "/DC-DC Converters/1V7_local")
			(pintype "passive")
		)
	)
)
